FILE_TYPE = CONNECTIVITY;
{Allegro Design Entry HDL 17.4-2019 S026 (4007227) 1/17/2022}
"PAGE_NUMBER" = 12;
0"NC";
1"M_C_CPU0_SA_DQ<31:0>";
2"M_C_CPU0_SB_DQ<31:0>";
3"M_C_CPU0_SA_CB<7:0>";
4"M_C_CPU0_SB_CB<7:0>";
5"M_C_CPU0_SA_DQS_DN<9:0>";
6"M_C_CPU0_SA_DQS_DP<9:0>";
7"M_C_CPU0_SB_DQS_DP<9:0>";
8"M_C_CPU0_SB_DQS_DN<9:0>";
9"M_C_CPU0_SA_CA<6:0>";
10"M_C_CPU0_SB_CA<6:0>";
11"M_C_CPU0_ALERT_N";
12"M_C_CPU0_ALERT_R_N";
13"TP_M_C_CPU0_SA_TEST39C";
14"M_C_CPU0_CLK_DP<0>";
15"M_C_CPU0_CLK_DN<0>";
16"M_C_CPU0_SA_RSP<0>";
17"M_C_CPU0_SA_CS_N<0>";
18"M_C_CPU0_SA_CS_N<1>";
19"M_C_CPU0_SA_PAR";
20"M_C_CPU0_SB_CS_N<0>";
21"M_C_CPU0_SB_CS_N<1>";
22"M_C_CPU0_SB_RSP<0>";
23"M_C_CPU0_SB_PAR";
24"M_C_CPU0_RESET_N";
25"M_C_CPU0_SB_DQS_DP<9>";
26"M_C_CPU0_SB_CA<6>";
27"M_C_CPU0_SB_DQS_DN<9>";
28"M_C_CPU0_SA_CA<6>";
29"M_C_CPU0_SB_CA<5>";
30"M_C_CPU0_SB_DQS_DN<8>";
31"M_C_CPU0_SA_CA<5>";
32"M_C_CPU0_SB_CA<4>";
33"M_C_CPU0_SA_CA<4>";
34"M_C_CPU0_SB_CA<3>";
35"M_C_CPU0_SA_CA<3>";
36"M_C_CPU0_SB_CA<2>";
37"M_C_CPU0_SA_CA<2>";
38"M_C_CPU0_SB_CA<1>";
39"M_C_CPU0_SA_CA<1>";
40"M_C_CPU0_SB_CA<0>";
41"M_C_CPU0_SA_CA<0>";
42"M_C_CPU0_SB_DQS_DP<7>";
43"M_C_CPU0_SB_DQS_DP<6>";
44"M_C_CPU0_SB_DQS_DP<5>";
45"M_C_CPU0_SB_DQS_DP<4>";
46"M_C_CPU0_SA_DQS_DP<9>";
47"M_C_CPU0_SB_DQS_DP<3>";
48"M_C_CPU0_SB_DQS_DN<7>";
49"M_C_CPU0_SB_DQS_DP<2>";
50"M_C_CPU0_SB_DQS_DN<6>";
51"M_C_CPU0_SB_DQS_DP<1>";
52"M_C_CPU0_SB_DQS_DN<5>";
53"M_C_CPU0_SB_DQS_DP<0>";
54"M_C_CPU0_SB_DQS_DN<4>";
55"M_C_CPU0_SA_DQS_DN<9>";
56"M_C_CPU0_SB_DQS_DN<3>";
57"M_C_CPU0_SA_DQS_DN<8>";
58"M_C_CPU0_SB_DQS_DN<2>";
59"M_C_CPU0_SB_DQS_DN<1>";
60"M_C_CPU0_SB_DQS_DN<0>";
61"M_C_CPU0_SB_DQS_DP<8>";
62"M_C_CPU0_SA_DQS_DN<0>";
63"M_C_CPU0_SA_DQS_DP<8>";
64"M_C_CPU0_SA_DQS_DP<7>";
65"M_C_CPU0_SA_DQS_DP<6>";
66"M_C_CPU0_SA_DQS_DP<5>";
67"M_C_CPU0_SA_DQS_DP<4>";
68"M_C_CPU0_SA_DQS_DP<3>";
69"M_C_CPU0_SA_DQS_DN<7>";
70"M_C_CPU0_SA_DQS_DP<2>";
71"M_C_CPU0_SA_DQS_DN<6>";
72"M_C_CPU0_SA_DQS_DP<1>";
73"M_C_CPU0_SA_DQS_DN<5>";
74"M_C_CPU0_SA_DQS_DP<0>";
75"M_C_CPU0_SA_DQS_DN<4>";
76"M_C_CPU0_SA_DQS_DN<3>";
77"M_C_CPU0_SA_DQS_DN<2>";
78"M_C_CPU0_SA_DQS_DN<1>";
79"M_C_CPU0_SB_CB<7>";
80"M_C_CPU0_SB_CB<6>";
81"M_C_CPU0_SB_CB<5>";
82"M_C_CPU0_SB_CB<4>";
83"M_C_CPU0_SB_CB<3>";
84"M_C_CPU0_SB_CB<2>";
85"M_C_CPU0_SA_CB<7>";
86"M_C_CPU0_SB_CB<1>";
87"M_C_CPU0_SB_CB<0>";
88"M_C_CPU0_SA_CB<4>";
89"M_C_CPU0_SA_CB<3>";
90"M_C_CPU0_SA_CB<2>";
91"M_C_CPU0_SA_CB<1>";
92"M_C_CPU0_SA_CB<0>";
93"M_C_CPU0_SB_DQ<29>";
94"M_C_CPU0_SB_DQ<28>";
95"M_C_CPU0_SB_DQ<27>";
96"M_C_CPU0_SB_DQ<26>";
97"M_C_CPU0_SB_DQ<25>";
98"M_C_CPU0_SB_DQ<24>";
99"M_C_CPU0_SB_DQ<23>";
100"M_C_CPU0_SB_DQ<22>";
101"M_C_CPU0_SB_DQ<21>";
102"M_C_CPU0_SA_CB<6>";
103"M_C_CPU0_SB_DQ<20>";
104"M_C_CPU0_SB_DQ<31>";
105"M_C_CPU0_SA_CB<5>";
106"M_C_CPU0_SB_DQ<30>";
107"M_C_CPU0_SB_DQ<7>";
108"M_C_CPU0_SB_DQ<6>";
109"M_C_CPU0_SB_DQ<5>";
110"M_C_CPU0_SB_DQ<4>";
111"M_C_CPU0_SB_DQ<3>";
112"M_C_CPU0_SB_DQ<2>";
113"M_C_CPU0_SB_DQ<19>";
114"M_C_CPU0_SB_DQ<18>";
115"M_C_CPU0_SB_DQ<17>";
116"M_C_CPU0_SB_DQ<16>";
117"M_C_CPU0_SB_DQ<15>";
118"M_C_CPU0_SB_DQ<14>";
119"M_C_CPU0_SB_DQ<13>";
120"M_C_CPU0_SB_DQ<12>";
121"M_C_CPU0_SB_DQ<11>";
122"M_C_CPU0_SB_DQ<10>";
123"M_C_CPU0_SB_DQ<9>";
124"M_C_CPU0_SB_DQ<8>";
125"M_C_CPU0_SA_DQ<24>";
126"M_C_CPU0_SA_DQ<23>";
127"M_C_CPU0_SA_DQ<22>";
128"M_C_CPU0_SA_DQ<21>";
129"M_C_CPU0_SA_DQ<20>";
130"M_C_CPU0_SA_DQ<31>";
131"M_C_CPU0_SA_DQ<30>";
132"M_C_CPU0_SB_DQ<1>";
133"M_C_CPU0_SB_DQ<0>";
134"M_C_CPU0_SA_DQ<19>";
135"M_C_CPU0_SA_DQ<18>";
136"M_C_CPU0_SA_DQ<29>";
137"M_C_CPU0_SA_DQ<17>";
138"M_C_CPU0_SA_DQ<28>";
139"M_C_CPU0_SA_DQ<16>";
140"M_C_CPU0_SA_DQ<27>";
141"M_C_CPU0_SA_DQ<26>";
142"M_C_CPU0_SA_DQ<25>";
143"M_C_CPU0_SA_DQ<8>";
144"M_C_CPU0_SA_DQ<13>";
145"M_C_CPU0_SA_DQ<7>";
146"M_C_CPU0_SA_DQ<12>";
147"M_C_CPU0_SA_DQ<6>";
148"M_C_CPU0_SA_DQ<11>";
149"M_C_CPU0_SA_DQ<5>";
150"M_C_CPU0_SA_DQ<10>";
151"M_C_CPU0_SA_DQ<4>";
152"M_C_CPU0_SA_DQ<3>";
153"M_C_CPU0_SA_DQ<2>";
154"M_C_CPU0_SA_DQ<1>";
155"M_C_CPU0_SA_DQ<0>";
156"M_C_CPU0_SA_DQ<15>";
157"M_C_CPU0_SA_DQ<9>";
158"M_C_CPU0_SA_DQ<14>";
%"GENOA_SP5"
"3","(-4775,3575)","0","pure_quanta","I159";
;
LOCATION"U25"
$SEC"3"
CDS_SEC"3"
PART_TYPE"SMLF"
MATERIAL"IO"
VALUE"SOCKET6096_13568-001"
CDS_LIB"pure_quanta"
CDS_LMAN_SYM_OUTLINE"-650,2525,650,-2525"
NEEDS_NO_SIZE"TRUE"
PART_NUMBER"DGA^6000030";
"TEST39C"
$PN"BF55"13;
"MC1_CLK_L"
$PN"BG57"0;
"MC1_CLK_H"
$PN"BF56"0;
"MC0_CLK_L"
$PN"BD56"15;
"MC0_CLK_H"
$PN"BC57"14;
"MCB_PAR"
$PN"BL57"23;
"MCA_PAR"
$PN"BC55"19;
"MCB_DQS_H9"
$PN"BV56"25;
"MCA_CHECK4"
$PN"AN57"88;
"MCA_DATA8"
$PN"L57"143;
"MCA_DATA13"
$PN"T55"144;
"MCA_DATA24"
$PN"AC57"125;
"MCA_DQS_L0"
$PN"H56"62;
"MCB0_CS_L0"
$PN"BM55"20;
"MCB1_CS_L0"
$PN"BL55"0;
"MCB_DATA7"
$PN"CH55"107;
"MCB_DQS_H7"
$PN"CV55"42;
"MCA_CHECK3"
$PN"AL55"89;
"MCA_DATA7"
$PN"L55"145;
"MCA_DATA12"
$PN"R57"146;
"MCA_DATA23"
$PN"AC55"126;
"MCB_DATA6"
$PN"CG57"108;
"MCB_DQS_H6"
$PN"CM55"43;
"MCA_CHECK2"
$PN"AK56"90;
"MCA_DATA6"
$PN"K56"147;
"MCA_DATA11"
$PN"N55"148;
"MCA_DATA22"
$PN"AB56"127;
"MCB_CA6"
$PN"BK56"26;
"MCB_DATA5"
$PN"CG55"109;
"MCB_DQS_H5"
$PN"CF55"44;
"MCB_DQS_L9"
$PN"BW57"27;
"MCA_CA6"
$PN"BB55"28;
"MCA_CHECK1"
$PN"AK55"91;
"MCA_DATA5"
$PN"K55"149;
"MCA_DATA10"
$PN"M56"150;
"MCA_DATA21"
$PN"AB55"128;
"MCB_CA5"
$PN"BK55"29;
"MCB_DATA4"
$PN"CF56"110;
"MCB_DQS_H4"
$PN"BY55"45;
"MCB_DQS_L8"
$PN"DC55"30;
"MCA_CA5"
$PN"BB56"31;
"MCA_CHECK0"
$PN"AJ57"92;
"MCA_DATA4"
$PN"J57"151;
"MCA_DATA20"
$PN"AA57"129;
"MCA_DATA31"
$PN"AJ55"130;
"MCA_DQS_H9"
$PN"AN55"46;
"MCB_CA4"
$PN"BJ55"32;
"MCB_DATA3"
$PN"CD55"111;
"MCB_DQS_H3"
$PN"DB56"47;
"MCB_DQS_L7"
$PN"CU55"48;
"MCA1_CS_L1"
$PN"AV55"0;
"MCA_CA4"
$PN"BA57"33;
"MCA_DATA3"
$PN"G55"152;
"MCA_DATA30"
$PN"AH56"131;
"MCA_DQS_H8"
$PN"AG55"63;
"MCB_CA3"
$PN"BJ57"34;
"MCB_DATA2"
$PN"CC57"112;
"MCB_DATA19"
$PN"CT55"113;
"MCB_DQS_H2"
$PN"CT56"49;
"MCB_DQS_L6"
$PN"CL55"50;
"MCA0_CS_L1"
$PN"AW55"18;
"MCA1_CS_L0"
$PN"AU57"0;
"MCA_CA3"
$PN"BA55"35;
"MCA_DATA2"
$PN"F56"153;
"MCA_DQS_H7"
$PN"AA55"64;
"MCB_CA2"
$PN"BH56"36;
"MCB_DATA1"
$PN"CC55"132;
"MCB_DATA18"
$PN"CR57"114;
"MCB_DATA29"
$PN"DE55"93;
"MCB_DQS_H1"
$PN"CK56"51;
"MCB_DQS_L5"
$PN"CE55"52;
"MCA0_CS_L0"
$PN"AV56"17;
"MCA_CA2"
$PN"AY55"37;
"MCA_DATA1"
$PN"F55"154;
"MCA_DQS_H6"
$PN"R55"65;
"MCB_CA1"
$PN"BH55"38;
"MCB_DATA0"
$PN"CB56"133;
"MCB_DATA17"
$PN"CR55"115;
"MCB_DATA28"
$PN"DD56"94;
"MCB_DQS_H0"
$PN"CD56"53;
"MCB_DQS_L4"
$PN"BW55"54;
"MCA_CA1"
$PN"AY56"39;
"MCA_DATA0"
$PN"E57"155;
"MCA_DQS_H5"
$PN"J55"66;
"MCA_DQS_L9"
$PN"AM55"55;
"MCB0_RSP_L"
$PN"BP56"22;
"MCB1_RSP_L"
$PN"BR57"0;
"MCB_CA0"
$PN"BG55"40;
"MCB_CHECK7"
$PN"BV55"79;
"MCB_DATA16"
$PN"CP56"116;
"MCB_DATA27"
$PN"DB55"95;
"MCB_DQS_L3"
$PN"DC57"56;
"MCA_CA0"
$PN"AW57"41;
"MCA_DQS_H4"
$PN"AL57"67;
"MCA_DQS_L8"
$PN"AF55"57;
"MCB_CHECK6"
$PN"BU57"80;
"MCB_DATA15"
$PN"CP55"117;
"MCB_DATA26"
$PN"DA57"96;
"MCB_DQS_L2"
$PN"CU57"58;
"MCA_DQS_H3"
$PN"AE57"68;
"MCA_DQS_L7"
$PN"Y55"69;
"MCB_CHECK5"
$PN"BU55"81;
"MCB_DATA14"
$PN"CN57"118;
"MCB_DATA25"
$PN"DA55"97;
"MCB_DQS_L1"
$PN"CL57"59;
"MCA_DATA19"
$PN"W55"134;
"MCA_DQS_H2"
$PN"W57"70;
"MCA_DQS_L6"
$PN"P55"71;
"MCB_CHECK4"
$PN"BT56"82;
"MCB_DATA13"
$PN"CN55"119;
"MCB_DATA24"
$PN"CY56"98;
"MCB_DQS_L0"
$PN"CE57"60;
"MCA_DATA18"
$PN"V56"135;
"MCA_DATA29"
$PN"AH55"136;
"MCA_DQS_H1"
$PN"N57"72;
"MCA_DQS_L5"
$PN"H55"73;
"MCB_CHECK3"
$PN"CB55"83;
"MCB_DATA12"
$PN"CM56"120;
"MCB_DATA23"
$PN"CY55"99;
"MCA_DATA17"
$PN"V55"137;
"MCA_DATA28"
$PN"AG57"138;
"MCA_DQS_H0"
$PN"G57"74;
"MCA_DQS_L4"
$PN"AM56"75;
"MCB_CHECK2"
$PN"CA57"84;
"MCB_DATA11"
$PN"CK55"121;
"MCB_DATA22"
$PN"CW57"100;
"MCA1_RSP_L"
$PN"BP55"0;
"MCA_CHECK7"
$PN"AR55"85;
"MCA_DATA16"
$PN"U57"139;
"MCA_DATA27"
$PN"AE55"140;
"MCA_DQS_L3"
$PN"AF56"76;
"MCB_CHECK1"
$PN"CA55"86;
"MCB_DATA10"
$PN"CJ57"122;
"MCB_DATA21"
$PN"CW55"101;
"MCA0_RSP_L"
$PN"BN55"16;
"MCA_CHECK6"
$PN"AP56"102;
"MCA_DATA15"
$PN"U55"156;
"MCA_DATA26"
$PN"AD56"141;
"MCA_DQS_L2"
$PN"Y56"77;
"MCB_CHECK0"
$PN"BY56"87;
"MCB_DATA9"
$PN"CJ55"123;
"MCB_DATA20"
$PN"CV56"103;
"MCB_DATA31"
$PN"DF55"104;
"MCA_CHECK5"
$PN"AP55"105;
"MCA_DATA9"
$PN"M55"157;
"MCA_DATA14"
$PN"T56"158;
"MCA_DATA25"
$PN"AD55"142;
"MCA_DQS_L1"
$PN"P56"78;
"MCB0_CS_L1"
$PN"BN57"21;
"MCB1_CS_L1"
$PN"BM56"0;
"MCB_DATA8"
$PN"CH56"124;
"MCB_DATA30"
$PN"DE57"106;
"MCB_DQS_H8"
$PN"DD55"61;
"MC_RESET_L"
$PN"AU55"24;
"MC_ALERT_L"
$PN"AT55"12;
%"TAP"
"1","(-3500,5900)","0","mstr_standard","I162";
;
CDS_LIB"mstr_standard"
BODY_TYPE"PLUMBING"
HDL_TAP"TRUE";
"B \NAC \NWC"1;
"S \NAC"
BN"1"154;
%"TAP"
"1","(-3500,5950)","0","mstr_standard","I163";
;
CDS_LIB"mstr_standard"
BODY_TYPE"PLUMBING"
HDL_TAP"TRUE";
"B \NAC \NWC"1;
"S \NAC"
BN"0"155;
%"TAP"
"1","(-3500,5850)","0","mstr_standard","I164";
;
CDS_LIB"mstr_standard"
BODY_TYPE"PLUMBING"
HDL_TAP"TRUE";
"B \NAC \NWC"1;
"S \NAC"
BN"2"153;
%"TAP"
"1","(-3500,5800)","0","mstr_standard","I165";
;
CDS_LIB"mstr_standard"
BODY_TYPE"PLUMBING"
HDL_TAP"TRUE";
"B \NAC \NWC"1;
"S \NAC"
BN"3"152;
%"TAP"
"1","(-3500,5750)","0","mstr_standard","I166";
;
CDS_LIB"mstr_standard"
BODY_TYPE"PLUMBING"
HDL_TAP"TRUE";
"B \NAC \NWC"1;
"S \NAC"
BN"4"151;
%"TAP"
"1","(-3500,5700)","0","mstr_standard","I167";
;
CDS_LIB"mstr_standard"
BODY_TYPE"PLUMBING"
HDL_TAP"TRUE";
"B \NAC \NWC"1;
"S \NAC"
BN"5"149;
%"TAP"
"1","(-3500,5650)","0","mstr_standard","I168";
;
CDS_LIB"mstr_standard"
BODY_TYPE"PLUMBING"
HDL_TAP"TRUE";
"B \NAC \NWC"1;
"S \NAC"
BN"6"147;
%"TAP"
"1","(-3500,5600)","0","mstr_standard","I169";
;
CDS_LIB"mstr_standard"
BODY_TYPE"PLUMBING"
HDL_TAP"TRUE";
"B \NAC \NWC"1;
"S \NAC"
BN"7"145;
%"TAP"
"1","(-3500,5500)","0","mstr_standard","I170";
;
CDS_LIB"mstr_standard"
BODY_TYPE"PLUMBING"
HDL_TAP"TRUE";
"B \NAC \NWC"1;
"S \NAC"
BN"8"143;
%"TAP"
"1","(-3500,5400)","0","mstr_standard","I171";
;
CDS_LIB"mstr_standard"
BODY_TYPE"PLUMBING"
HDL_TAP"TRUE";
"B \NAC \NWC"1;
"S \NAC"
BN"10"150;
%"TAP"
"1","(-3500,5450)","0","mstr_standard","I172";
;
CDS_LIB"mstr_standard"
BODY_TYPE"PLUMBING"
HDL_TAP"TRUE";
"B \NAC \NWC"1;
"S \NAC"
BN"9"157;
%"TAP"
"1","(-3500,5350)","0","mstr_standard","I173";
;
CDS_LIB"mstr_standard"
BODY_TYPE"PLUMBING"
HDL_TAP"TRUE";
"B \NAC \NWC"1;
"S \NAC"
BN"11"148;
%"TAP"
"1","(-3500,5300)","0","mstr_standard","I174";
;
CDS_LIB"mstr_standard"
BODY_TYPE"PLUMBING"
HDL_TAP"TRUE";
"B \NAC \NWC"1;
"S \NAC"
BN"12"146;
%"TAP"
"1","(-3500,5250)","0","mstr_standard","I175";
;
CDS_LIB"mstr_standard"
BODY_TYPE"PLUMBING"
HDL_TAP"TRUE";
"B \NAC \NWC"1;
"S \NAC"
BN"13"144;
%"TAP"
"1","(-3500,5200)","0","mstr_standard","I176";
;
CDS_LIB"mstr_standard"
BODY_TYPE"PLUMBING"
HDL_TAP"TRUE";
"B \NAC \NWC"1;
"S \NAC"
BN"14"158;
%"TAP"
"1","(-3500,5150)","0","mstr_standard","I177";
;
CDS_LIB"mstr_standard"
BODY_TYPE"PLUMBING"
HDL_TAP"TRUE";
"B \NAC \NWC"1;
"S \NAC"
BN"15"156;
%"TAP"
"1","(-3500,5050)","0","mstr_standard","I178";
;
CDS_LIB"mstr_standard"
BODY_TYPE"PLUMBING"
HDL_TAP"TRUE";
"B \NAC \NWC"1;
"S \NAC"
BN"16"139;
%"TAP"
"1","(-3500,5000)","0","mstr_standard","I179";
;
CDS_LIB"mstr_standard"
BODY_TYPE"PLUMBING"
HDL_TAP"TRUE";
"B \NAC \NWC"1;
"S \NAC"
BN"17"137;
%"TAP"
"1","(-3500,4950)","0","mstr_standard","I180";
;
CDS_LIB"mstr_standard"
BODY_TYPE"PLUMBING"
HDL_TAP"TRUE";
"B \NAC \NWC"1;
"S \NAC"
BN"18"135;
%"TAP"
"1","(-3500,4900)","0","mstr_standard","I181";
;
CDS_LIB"mstr_standard"
BODY_TYPE"PLUMBING"
HDL_TAP"TRUE";
"B \NAC \NWC"1;
"S \NAC"
BN"19"134;
%"TAP"
"1","(-3500,4850)","0","mstr_standard","I182";
;
CDS_LIB"mstr_standard"
BODY_TYPE"PLUMBING"
HDL_TAP"TRUE";
"B \NAC \NWC"1;
"S \NAC"
BN"20"129;
%"TAP"
"1","(-3500,4800)","0","mstr_standard","I183";
;
CDS_LIB"mstr_standard"
BODY_TYPE"PLUMBING"
HDL_TAP"TRUE";
"B \NAC \NWC"1;
"S \NAC"
BN"21"128;
%"TAP"
"1","(-3500,4750)","0","mstr_standard","I184";
;
CDS_LIB"mstr_standard"
BODY_TYPE"PLUMBING"
HDL_TAP"TRUE";
"B \NAC \NWC"1;
"S \NAC"
BN"22"127;
%"TAP"
"1","(-3500,4700)","0","mstr_standard","I185";
;
CDS_LIB"mstr_standard"
BODY_TYPE"PLUMBING"
HDL_TAP"TRUE";
"B \NAC \NWC"1;
"S \NAC"
BN"23"126;
%"TAP"
"1","(-3500,4600)","0","mstr_standard","I186";
;
CDS_LIB"mstr_standard"
BODY_TYPE"PLUMBING"
HDL_TAP"TRUE";
"B \NAC \NWC"1;
"S \NAC"
BN"24"125;
%"TAP"
"1","(-3500,4550)","0","mstr_standard","I187";
;
CDS_LIB"mstr_standard"
BODY_TYPE"PLUMBING"
HDL_TAP"TRUE";
"B \NAC \NWC"1;
"S \NAC"
BN"25"142;
%"TAP"
"1","(-3500,4500)","0","mstr_standard","I188";
;
CDS_LIB"mstr_standard"
BODY_TYPE"PLUMBING"
HDL_TAP"TRUE";
"B \NAC \NWC"1;
"S \NAC"
BN"26"141;
%"TAP"
"1","(-3500,4450)","0","mstr_standard","I189";
;
CDS_LIB"mstr_standard"
BODY_TYPE"PLUMBING"
HDL_TAP"TRUE";
"B \NAC \NWC"1;
"S \NAC"
BN"27"140;
%"TAP"
"1","(-3500,4400)","0","mstr_standard","I190";
;
CDS_LIB"mstr_standard"
BODY_TYPE"PLUMBING"
HDL_TAP"TRUE";
"B \NAC \NWC"1;
"S \NAC"
BN"28"138;
%"TAP"
"1","(-3500,4350)","0","mstr_standard","I191";
;
CDS_LIB"mstr_standard"
BODY_TYPE"PLUMBING"
HDL_TAP"TRUE";
"B \NAC \NWC"1;
"S \NAC"
BN"29"136;
%"TAP"
"1","(-3500,4300)","0","mstr_standard","I192";
;
CDS_LIB"mstr_standard"
BODY_TYPE"PLUMBING"
HDL_TAP"TRUE";
"B \NAC \NWC"1;
"S \NAC"
BN"30"131;
%"TAP"
"1","(-3500,4250)","0","mstr_standard","I193";
;
CDS_LIB"mstr_standard"
BODY_TYPE"PLUMBING"
HDL_TAP"TRUE";
"B \NAC \NWC"1;
"S \NAC"
BN"31"130;
%"TAP"
"1","(-3500,4100)","0","mstr_standard","I194";
;
CDS_LIB"mstr_standard"
BODY_TYPE"PLUMBING"
HDL_TAP"TRUE";
"B \NAC \NWC"2;
"S \NAC"
BN"1"132;
%"TAP"
"1","(-3500,4150)","0","mstr_standard","I195";
;
CDS_LIB"mstr_standard"
BODY_TYPE"PLUMBING"
HDL_TAP"TRUE";
"B \NAC \NWC"2;
"S \NAC"
BN"0"133;
%"TAP"
"1","(-3500,4050)","0","mstr_standard","I197";
;
CDS_LIB"mstr_standard"
BODY_TYPE"PLUMBING"
HDL_TAP"TRUE";
"B \NAC \NWC"2;
"S \NAC"
BN"2"112;
%"TAP"
"1","(-3500,4000)","0","mstr_standard","I198";
;
CDS_LIB"mstr_standard"
BODY_TYPE"PLUMBING"
HDL_TAP"TRUE";
"B \NAC \NWC"2;
"S \NAC"
BN"3"111;
%"TAP"
"1","(-3500,3950)","0","mstr_standard","I199";
;
CDS_LIB"mstr_standard"
BODY_TYPE"PLUMBING"
HDL_TAP"TRUE";
"B \NAC \NWC"2;
"S \NAC"
BN"4"110;
%"TAP"
"1","(-3500,3900)","0","mstr_standard","I200";
;
CDS_LIB"mstr_standard"
BODY_TYPE"PLUMBING"
HDL_TAP"TRUE";
"B \NAC \NWC"2;
"S \NAC"
BN"5"109;
%"TAP"
"1","(-3500,3850)","0","mstr_standard","I201";
;
CDS_LIB"mstr_standard"
BODY_TYPE"PLUMBING"
HDL_TAP"TRUE";
"B \NAC \NWC"2;
"S \NAC"
BN"6"108;
%"TAP"
"1","(-3500,3800)","0","mstr_standard","I202";
;
CDS_LIB"mstr_standard"
BODY_TYPE"PLUMBING"
HDL_TAP"TRUE";
"B \NAC \NWC"2;
"S \NAC"
BN"7"107;
%"TAP"
"1","(-3500,3700)","0","mstr_standard","I203";
;
CDS_LIB"mstr_standard"
BODY_TYPE"PLUMBING"
HDL_TAP"TRUE";
"B \NAC \NWC"2;
"S \NAC"
BN"8"124;
%"TAP"
"1","(-3500,3650)","0","mstr_standard","I204";
;
CDS_LIB"mstr_standard"
BODY_TYPE"PLUMBING"
HDL_TAP"TRUE";
"B \NAC \NWC"2;
"S \NAC"
BN"9"123;
%"TAP"
"1","(-3500,3600)","0","mstr_standard","I205";
;
CDS_LIB"mstr_standard"
BODY_TYPE"PLUMBING"
HDL_TAP"TRUE";
"B \NAC \NWC"2;
"S \NAC"
BN"10"122;
%"TAP"
"1","(-3500,3550)","0","mstr_standard","I206";
;
CDS_LIB"mstr_standard"
BODY_TYPE"PLUMBING"
HDL_TAP"TRUE";
"B \NAC \NWC"2;
"S \NAC"
BN"11"121;
%"TAP"
"1","(-3500,3500)","0","mstr_standard","I207";
;
CDS_LIB"mstr_standard"
BODY_TYPE"PLUMBING"
HDL_TAP"TRUE";
"B \NAC \NWC"2;
"S \NAC"
BN"12"120;
%"TAP"
"1","(-3500,3400)","0","mstr_standard","I208";
;
CDS_LIB"mstr_standard"
BODY_TYPE"PLUMBING"
HDL_TAP"TRUE";
"B \NAC \NWC"2;
"S \NAC"
BN"14"118;
%"TAP"
"1","(-3500,3350)","0","mstr_standard","I209";
;
CDS_LIB"mstr_standard"
BODY_TYPE"PLUMBING"
HDL_TAP"TRUE";
"B \NAC \NWC"2;
"S \NAC"
BN"15"117;
%"TAP"
"1","(-3500,3450)","0","mstr_standard","I210";
;
CDS_LIB"mstr_standard"
BODY_TYPE"PLUMBING"
HDL_TAP"TRUE";
"B \NAC \NWC"2;
"S \NAC"
BN"13"119;
%"TAP"
"1","(-3500,3250)","0","mstr_standard","I211";
;
CDS_LIB"mstr_standard"
BODY_TYPE"PLUMBING"
HDL_TAP"TRUE";
"B \NAC \NWC"2;
"S \NAC"
BN"16"116;
%"TAP"
"1","(-3500,3200)","0","mstr_standard","I212";
;
CDS_LIB"mstr_standard"
BODY_TYPE"PLUMBING"
HDL_TAP"TRUE";
"B \NAC \NWC"2;
"S \NAC"
BN"17"115;
%"TAP"
"1","(-3500,3150)","0","mstr_standard","I213";
;
CDS_LIB"mstr_standard"
BODY_TYPE"PLUMBING"
HDL_TAP"TRUE";
"B \NAC \NWC"2;
"S \NAC"
BN"18"114;
%"TAP"
"1","(-3500,3100)","0","mstr_standard","I214";
;
CDS_LIB"mstr_standard"
BODY_TYPE"PLUMBING"
HDL_TAP"TRUE";
"B \NAC \NWC"2;
"S \NAC"
BN"19"113;
%"TAP"
"1","(-3500,2950)","0","mstr_standard","I215";
;
CDS_LIB"mstr_standard"
BODY_TYPE"PLUMBING"
HDL_TAP"TRUE";
"B \NAC \NWC"2;
"S \NAC"
BN"22"100;
%"TAP"
"1","(-3500,3050)","0","mstr_standard","I216";
;
CDS_LIB"mstr_standard"
BODY_TYPE"PLUMBING"
HDL_TAP"TRUE";
"B \NAC \NWC"2;
"S \NAC"
BN"20"103;
%"TAP"
"1","(-3500,2900)","0","mstr_standard","I217";
;
CDS_LIB"mstr_standard"
BODY_TYPE"PLUMBING"
HDL_TAP"TRUE";
"B \NAC \NWC"2;
"S \NAC"
BN"23"99;
%"TAP"
"1","(-3500,3000)","0","mstr_standard","I218";
;
CDS_LIB"mstr_standard"
BODY_TYPE"PLUMBING"
HDL_TAP"TRUE";
"B \NAC \NWC"2;
"S \NAC"
BN"21"101;
%"TAP"
"1","(-3500,2800)","0","mstr_standard","I219";
;
CDS_LIB"mstr_standard"
BODY_TYPE"PLUMBING"
HDL_TAP"TRUE";
"B \NAC \NWC"2;
"S \NAC"
BN"24"98;
%"TAP"
"1","(-3500,2700)","0","mstr_standard","I220";
;
CDS_LIB"mstr_standard"
BODY_TYPE"PLUMBING"
HDL_TAP"TRUE";
"B \NAC \NWC"2;
"S \NAC"
BN"26"96;
%"TAP"
"1","(-3500,2750)","0","mstr_standard","I221";
;
CDS_LIB"mstr_standard"
BODY_TYPE"PLUMBING"
HDL_TAP"TRUE";
"B \NAC \NWC"2;
"S \NAC"
BN"25"97;
%"TAP"
"1","(-3500,2650)","0","mstr_standard","I222";
;
CDS_LIB"mstr_standard"
BODY_TYPE"PLUMBING"
HDL_TAP"TRUE";
"B \NAC \NWC"2;
"S \NAC"
BN"27"95;
%"TAP"
"1","(-3500,2600)","0","mstr_standard","I223";
;
CDS_LIB"mstr_standard"
BODY_TYPE"PLUMBING"
HDL_TAP"TRUE";
"B \NAC \NWC"2;
"S \NAC"
BN"28"94;
%"TAP"
"1","(-3500,2550)","0","mstr_standard","I224";
;
CDS_LIB"mstr_standard"
BODY_TYPE"PLUMBING"
HDL_TAP"TRUE";
"B \NAC \NWC"2;
"S \NAC"
BN"29"93;
%"TAP"
"1","(-3500,2500)","0","mstr_standard","I225";
;
CDS_LIB"mstr_standard"
BODY_TYPE"PLUMBING"
HDL_TAP"TRUE";
"B \NAC \NWC"2;
"S \NAC"
BN"30"106;
%"TAP"
"1","(-3500,2450)","0","mstr_standard","I226";
;
CDS_LIB"mstr_standard"
BODY_TYPE"PLUMBING"
HDL_TAP"TRUE";
"B \NAC \NWC"2;
"S \NAC"
BN"31"104;
%"TAP"
"1","(-3500,2350)","0","mstr_standard","I227";
;
CDS_LIB"mstr_standard"
BODY_TYPE"PLUMBING"
HDL_TAP"TRUE";
"B \NAC \NWC"3;
"S \NAC"
BN"0"92;
%"TAP"
"1","(-3500,2300)","0","mstr_standard","I228";
;
CDS_LIB"mstr_standard"
BODY_TYPE"PLUMBING"
HDL_TAP"TRUE";
"B \NAC \NWC"3;
"S \NAC"
BN"1"91;
%"TAP"
"1","(-3500,2250)","0","mstr_standard","I229";
;
CDS_LIB"mstr_standard"
BODY_TYPE"PLUMBING"
HDL_TAP"TRUE";
"B \NAC \NWC"3;
"S \NAC"
BN"2"90;
%"TAP"
"1","(-3500,2200)","0","mstr_standard","I230";
;
CDS_LIB"mstr_standard"
BODY_TYPE"PLUMBING"
HDL_TAP"TRUE";
"B \NAC \NWC"3;
"S \NAC"
BN"3"89;
%"TAP"
"1","(-3500,2150)","0","mstr_standard","I231";
;
CDS_LIB"mstr_standard"
BODY_TYPE"PLUMBING"
HDL_TAP"TRUE";
"B \NAC \NWC"3;
"S \NAC"
BN"4"88;
%"TAP"
"1","(-3500,2100)","0","mstr_standard","I232";
;
CDS_LIB"mstr_standard"
BODY_TYPE"PLUMBING"
HDL_TAP"TRUE";
"B \NAC \NWC"3;
"S \NAC"
BN"5"105;
%"TAP"
"1","(-3500,2050)","0","mstr_standard","I233";
;
CDS_LIB"mstr_standard"
BODY_TYPE"PLUMBING"
HDL_TAP"TRUE";
"B \NAC \NWC"3;
"S \NAC"
BN"6"102;
%"TAP"
"1","(-3500,2000)","0","mstr_standard","I235";
;
CDS_LIB"mstr_standard"
BODY_TYPE"PLUMBING"
HDL_TAP"TRUE";
"B \NAC \NWC"3;
"S \NAC"
BN"7"85;
%"TAP"
"1","(-3500,1900)","0","mstr_standard","I236";
;
CDS_LIB"mstr_standard"
BODY_TYPE"PLUMBING"
HDL_TAP"TRUE";
"B \NAC \NWC"4;
"S \NAC"
BN"0"87;
%"TAP"
"1","(-3500,1850)","0","mstr_standard","I237";
;
CDS_LIB"mstr_standard"
BODY_TYPE"PLUMBING"
HDL_TAP"TRUE";
"B \NAC \NWC"4;
"S \NAC"
BN"1"86;
%"TAP"
"1","(-3500,1800)","0","mstr_standard","I238";
;
CDS_LIB"mstr_standard"
BODY_TYPE"PLUMBING"
HDL_TAP"TRUE";
"B \NAC \NWC"4;
"S \NAC"
BN"2"84;
%"TAP"
"1","(-3500,1750)","0","mstr_standard","I239";
;
CDS_LIB"mstr_standard"
BODY_TYPE"PLUMBING"
HDL_TAP"TRUE";
"B \NAC \NWC"4;
"S \NAC"
BN"3"83;
%"TAP"
"1","(-3500,1700)","0","mstr_standard","I240";
;
CDS_LIB"mstr_standard"
BODY_TYPE"PLUMBING"
HDL_TAP"TRUE";
"B \NAC \NWC"4;
"S \NAC"
BN"4"82;
%"TAP"
"1","(-3500,1650)","0","mstr_standard","I241";
;
CDS_LIB"mstr_standard"
BODY_TYPE"PLUMBING"
HDL_TAP"TRUE";
"B \NAC \NWC"4;
"S \NAC"
BN"5"81;
%"TAP"
"1","(-3500,1550)","0","mstr_standard","I242";
;
CDS_LIB"mstr_standard"
BODY_TYPE"PLUMBING"
HDL_TAP"TRUE";
"B \NAC \NWC"4;
"S \NAC"
BN"7"79;
%"TAP"
"1","(-3500,1600)","0","mstr_standard","I243";
;
CDS_LIB"mstr_standard"
BODY_TYPE"PLUMBING"
HDL_TAP"TRUE";
"B \NAC \NWC"4;
"S \NAC"
BN"6"80;
%"TAP"
"1","(-5925,5950)","2","mstr_standard","I244";
;
CDS_LIB"mstr_standard"
BODY_TYPE"PLUMBING"
HDL_TAP"TRUE";
"B \NAC \NWC"6;
"S \NAC"
BN"0"74;
%"TAP"
"1","(-5925,5850)","2","mstr_standard","I245";
;
CDS_LIB"mstr_standard"
BODY_TYPE"PLUMBING"
HDL_TAP"TRUE";
"B \NAC \NWC"6;
"S \NAC"
BN"1"72;
%"TAP"
"1","(-5925,5750)","2","mstr_standard","I246";
;
CDS_LIB"mstr_standard"
BODY_TYPE"PLUMBING"
HDL_TAP"TRUE";
"B \NAC \NWC"6;
"S \NAC"
BN"2"70;
%"TAP"
"1","(-5925,5650)","2","mstr_standard","I247";
;
CDS_LIB"mstr_standard"
BODY_TYPE"PLUMBING"
HDL_TAP"TRUE";
"B \NAC \NWC"6;
"S \NAC"
BN"3"68;
%"TAP"
"1","(-5925,5550)","2","mstr_standard","I248";
;
CDS_LIB"mstr_standard"
BODY_TYPE"PLUMBING"
HDL_TAP"TRUE";
"B \NAC \NWC"6;
"S \NAC"
BN"4"67;
%"TAP"
"1","(-5925,5450)","2","mstr_standard","I249";
;
CDS_LIB"mstr_standard"
BODY_TYPE"PLUMBING"
HDL_TAP"TRUE";
"B \NAC \NWC"6;
"S \NAC"
BN"5"66;
%"TAP"
"1","(-5925,5350)","2","mstr_standard","I250";
;
CDS_LIB"mstr_standard"
BODY_TYPE"PLUMBING"
HDL_TAP"TRUE";
"B \NAC \NWC"6;
"S \NAC"
BN"6"65;
%"TAP"
"1","(-5925,5250)","2","mstr_standard","I251";
;
CDS_LIB"mstr_standard"
BODY_TYPE"PLUMBING"
HDL_TAP"TRUE";
"B \NAC \NWC"6;
"S \NAC"
BN"7"64;
%"TAP"
"1","(-5925,5150)","2","mstr_standard","I252";
;
CDS_LIB"mstr_standard"
BODY_TYPE"PLUMBING"
HDL_TAP"TRUE";
"B \NAC \NWC"6;
"S \NAC"
BN"8"63;
%"TAP"
"1","(-5925,5050)","2","mstr_standard","I253";
;
CDS_LIB"mstr_standard"
BODY_TYPE"PLUMBING"
HDL_TAP"TRUE";
"B \NAC \NWC"6;
"S \NAC"
BN"9"46;
%"TAP"
"1","(-5925,4900)","2","mstr_standard","I254";
;
CDS_LIB"mstr_standard"
BODY_TYPE"PLUMBING"
HDL_TAP"TRUE";
"B \NAC \NWC"7;
"S \NAC"
BN"0"53;
%"TAP"
"1","(-5925,4800)","2","mstr_standard","I255";
;
CDS_LIB"mstr_standard"
BODY_TYPE"PLUMBING"
HDL_TAP"TRUE";
"B \NAC \NWC"7;
"S \NAC"
BN"1"51;
%"TAP"
"1","(-5925,4700)","2","mstr_standard","I256";
;
CDS_LIB"mstr_standard"
BODY_TYPE"PLUMBING"
HDL_TAP"TRUE";
"B \NAC \NWC"7;
"S \NAC"
BN"2"49;
%"TAP"
"1","(-5925,4500)","2","mstr_standard","I257";
;
CDS_LIB"mstr_standard"
BODY_TYPE"PLUMBING"
HDL_TAP"TRUE";
"B \NAC \NWC"7;
"S \NAC"
BN"4"45;
%"TAP"
"1","(-5925,4600)","2","mstr_standard","I258";
;
CDS_LIB"mstr_standard"
BODY_TYPE"PLUMBING"
HDL_TAP"TRUE";
"B \NAC \NWC"7;
"S \NAC"
BN"3"47;
%"TAP"
"1","(-5925,4400)","2","mstr_standard","I259";
;
CDS_LIB"mstr_standard"
BODY_TYPE"PLUMBING"
HDL_TAP"TRUE";
"B \NAC \NWC"7;
"S \NAC"
BN"5"44;
%"TAP"
"1","(-5925,4300)","2","mstr_standard","I260";
;
CDS_LIB"mstr_standard"
BODY_TYPE"PLUMBING"
HDL_TAP"TRUE";
"B \NAC \NWC"7;
"S \NAC"
BN"6"43;
%"TAP"
"1","(-5925,4100)","2","mstr_standard","I261";
;
CDS_LIB"mstr_standard"
BODY_TYPE"PLUMBING"
HDL_TAP"TRUE";
"B \NAC \NWC"7;
"S \NAC"
BN"8"61;
%"TAP"
"1","(-5925,4200)","2","mstr_standard","I262";
;
CDS_LIB"mstr_standard"
BODY_TYPE"PLUMBING"
HDL_TAP"TRUE";
"B \NAC \NWC"7;
"S \NAC"
BN"7"42;
%"TAP"
"1","(-6125,5800)","2","mstr_standard","I263";
;
CDS_LIB"mstr_standard"
BODY_TYPE"PLUMBING"
HDL_TAP"TRUE";
"B \NAC \NWC"5;
"S \NAC"
BN"1"78;
%"TAP"
"1","(-6125,5700)","2","mstr_standard","I264";
;
CDS_LIB"mstr_standard"
BODY_TYPE"PLUMBING"
HDL_TAP"TRUE";
"B \NAC \NWC"5;
"S \NAC"
BN"2"77;
%"TAP"
"1","(-6125,5900)","2","mstr_standard","I265";
;
CDS_LIB"mstr_standard"
BODY_TYPE"PLUMBING"
HDL_TAP"TRUE";
"B \NAC \NWC"5;
"S \NAC"
BN"0"62;
%"TAP"
"1","(-6125,5400)","2","mstr_standard","I266";
;
CDS_LIB"mstr_standard"
BODY_TYPE"PLUMBING"
HDL_TAP"TRUE";
"B \NAC \NWC"5;
"S \NAC"
BN"5"73;
%"TAP"
"1","(-6125,5600)","2","mstr_standard","I267";
;
CDS_LIB"mstr_standard"
BODY_TYPE"PLUMBING"
HDL_TAP"TRUE";
"B \NAC \NWC"5;
"S \NAC"
BN"3"76;
%"TAP"
"1","(-6125,5500)","2","mstr_standard","I268";
;
CDS_LIB"mstr_standard"
BODY_TYPE"PLUMBING"
HDL_TAP"TRUE";
"B \NAC \NWC"5;
"S \NAC"
BN"4"75;
%"TAP"
"1","(-6125,5100)","2","mstr_standard","I269";
;
CDS_LIB"mstr_standard"
BODY_TYPE"PLUMBING"
HDL_TAP"TRUE";
"B \NAC \NWC"5;
"S \NAC"
BN"8"57;
%"TAP"
"1","(-6125,5200)","2","mstr_standard","I270";
;
CDS_LIB"mstr_standard"
BODY_TYPE"PLUMBING"
HDL_TAP"TRUE";
"B \NAC \NWC"5;
"S \NAC"
BN"7"69;
%"TAP"
"1","(-6125,5300)","2","mstr_standard","I271";
;
CDS_LIB"mstr_standard"
BODY_TYPE"PLUMBING"
HDL_TAP"TRUE";
"B \NAC \NWC"5;
"S \NAC"
BN"6"71;
%"TAP"
"1","(-6125,4850)","2","mstr_standard","I274";
;
CDS_LIB"mstr_standard"
BODY_TYPE"PLUMBING"
HDL_TAP"TRUE";
"B \NAC \NWC"8;
"S \NAC"
BN"0"60;
%"TAP"
"1","(-6125,5000)","2","mstr_standard","I275";
;
CDS_LIB"mstr_standard"
BODY_TYPE"PLUMBING"
HDL_TAP"TRUE";
"B \NAC \NWC"5;
"S \NAC"
BN"9"55;
%"TAP"
"1","(-6125,4650)","2","mstr_standard","I276";
;
CDS_LIB"mstr_standard"
BODY_TYPE"PLUMBING"
HDL_TAP"TRUE";
"B \NAC \NWC"8;
"S \NAC"
BN"2"58;
%"TAP"
"1","(-6125,4750)","2","mstr_standard","I277";
;
CDS_LIB"mstr_standard"
BODY_TYPE"PLUMBING"
HDL_TAP"TRUE";
"B \NAC \NWC"8;
"S \NAC"
BN"1"59;
%"TAP"
"1","(-6125,4350)","2","mstr_standard","I278";
;
CDS_LIB"mstr_standard"
BODY_TYPE"PLUMBING"
HDL_TAP"TRUE";
"B \NAC \NWC"8;
"S \NAC"
BN"5"52;
%"TAP"
"1","(-6125,4550)","2","mstr_standard","I279";
;
CDS_LIB"mstr_standard"
BODY_TYPE"PLUMBING"
HDL_TAP"TRUE";
"B \NAC \NWC"8;
"S \NAC"
BN"3"56;
%"TAP"
"1","(-6125,4450)","2","mstr_standard","I280";
;
CDS_LIB"mstr_standard"
BODY_TYPE"PLUMBING"
HDL_TAP"TRUE";
"B \NAC \NWC"8;
"S \NAC"
BN"4"54;
%"TAP"
"1","(-6125,4150)","2","mstr_standard","I281";
;
CDS_LIB"mstr_standard"
BODY_TYPE"PLUMBING"
HDL_TAP"TRUE";
"B \NAC \NWC"8;
"S \NAC"
BN"7"48;
%"TAP"
"1","(-6125,4250)","2","mstr_standard","I282";
;
CDS_LIB"mstr_standard"
BODY_TYPE"PLUMBING"
HDL_TAP"TRUE";
"B \NAC \NWC"8;
"S \NAC"
BN"6"50;
%"TAP"
"1","(-5925,4000)","2","mstr_standard","I285";
;
CDS_LIB"mstr_standard"
BODY_TYPE"PLUMBING"
HDL_TAP"TRUE";
"B \NAC \NWC"7;
"S \NAC"
BN"9"25;
%"TAP"
"1","(-6125,3950)","2","mstr_standard","I286";
;
CDS_LIB"mstr_standard"
BODY_TYPE"PLUMBING"
HDL_TAP"TRUE";
"B \NAC \NWC"8;
"S \NAC"
BN"9"27;
%"TAP"
"1","(-6125,4050)","2","mstr_standard","I287";
;
CDS_LIB"mstr_standard"
BODY_TYPE"PLUMBING"
HDL_TAP"TRUE";
"B \NAC \NWC"8;
"S \NAC"
BN"8"30;
%"TAP"
"1","(-6125,3750)","2","mstr_standard","I288";
;
CDS_LIB"mstr_standard"
BODY_TYPE"PLUMBING"
HDL_TAP"TRUE";
"B \NAC \NWC"9;
"S \NAC"
BN"1"39;
%"TAP"
"1","(-6125,3800)","2","mstr_standard","I289";
;
CDS_LIB"mstr_standard"
BODY_TYPE"PLUMBING"
HDL_TAP"TRUE";
"B \NAC \NWC"9;
"S \NAC"
BN"0"41;
%"TAP"
"1","(-6125,3700)","2","mstr_standard","I290";
;
CDS_LIB"mstr_standard"
BODY_TYPE"PLUMBING"
HDL_TAP"TRUE";
"B \NAC \NWC"9;
"S \NAC"
BN"2"37;
%"TAP"
"1","(-6125,3650)","2","mstr_standard","I291";
;
CDS_LIB"mstr_standard"
BODY_TYPE"PLUMBING"
HDL_TAP"TRUE";
"B \NAC \NWC"9;
"S \NAC"
BN"3"35;
%"TAP"
"1","(-6125,3600)","2","mstr_standard","I292";
;
CDS_LIB"mstr_standard"
BODY_TYPE"PLUMBING"
HDL_TAP"TRUE";
"B \NAC \NWC"9;
"S \NAC"
BN"4"33;
%"TAP"
"1","(-6125,3550)","2","mstr_standard","I293";
;
CDS_LIB"mstr_standard"
BODY_TYPE"PLUMBING"
HDL_TAP"TRUE";
"B \NAC \NWC"9;
"S \NAC"
BN"5"31;
%"TAP"
"1","(-6125,3500)","2","mstr_standard","I294";
;
CDS_LIB"mstr_standard"
BODY_TYPE"PLUMBING"
HDL_TAP"TRUE";
"B \NAC \NWC"9;
"S \NAC"
BN"6"28;
%"TAP"
"1","(-6125,3400)","2","mstr_standard","I295";
;
CDS_LIB"mstr_standard"
BODY_TYPE"PLUMBING"
HDL_TAP"TRUE";
"B \NAC \NWC"10;
"S \NAC"
BN"0"40;
%"TAP"
"1","(-6125,3350)","2","mstr_standard","I296";
;
CDS_LIB"mstr_standard"
BODY_TYPE"PLUMBING"
HDL_TAP"TRUE";
"B \NAC \NWC"10;
"S \NAC"
BN"1"38;
%"TAP"
"1","(-6125,3250)","2","mstr_standard","I297";
;
CDS_LIB"mstr_standard"
BODY_TYPE"PLUMBING"
HDL_TAP"TRUE";
"B \NAC \NWC"10;
"S \NAC"
BN"3"34;
%"TAP"
"1","(-6125,3300)","2","mstr_standard","I298";
;
CDS_LIB"mstr_standard"
BODY_TYPE"PLUMBING"
HDL_TAP"TRUE";
"B \NAC \NWC"10;
"S \NAC"
BN"2"36;
%"TAP"
"1","(-6125,3200)","2","mstr_standard","I299";
;
CDS_LIB"mstr_standard"
BODY_TYPE"PLUMBING"
HDL_TAP"TRUE";
"B \NAC \NWC"10;
"S \NAC"
BN"4"32;
%"TAP"
"1","(-6125,3150)","2","mstr_standard","I300";
;
CDS_LIB"mstr_standard"
BODY_TYPE"PLUMBING"
HDL_TAP"TRUE";
"B \NAC \NWC"10;
"S \NAC"
BN"5"29;
%"TAP"
"1","(-6125,3100)","2","mstr_standard","I301";
;
CDS_LIB"mstr_standard"
BODY_TYPE"PLUMBING"
HDL_TAP"TRUE";
"B \NAC \NWC"10;
"S \NAC"
BN"6"26;
%"Q_RES"
"1","(-7050,2100)","0","pure_quanta","I314";
;
LOCATION"R377"
$SEC"1"
CDS_SEC"1"
PACK_TYPE"0402LF"
TOLERANCE"1%"
VALUE"15"
MATERIAL"CHIP"
WATTAGE"1/16W"
CDS_LIB"pure_quanta"
PART_NUMBER"CS01502FB03";
"B"
$PN"2"12;
"A"
$PN"1"11;
END.
